(kicad_pcb
	(version 20241229)
	(generator "pcbnew")
	(generator_version "9.0")
	(general
		(thickness 1.294)
		(legacy_teardrops no)
	)
	(paper "A3")
	(title_block
		(title "Kintex 410T devboard")
		(date "2024-04-03")
		(rev "1.1.2")
		(comment 9 "footprints 176-181 of 975")
	)
	(layers
		(0 "F.Cu" mixed)
		(4 "In1.Cu" power)
		(6 "In2.Cu" power)
		(8 "In3.Cu" mixed)
		(10 "In4.Cu" power)
		(12 "In5.Cu" mixed)
		(14 "In6.Cu" power)
		(16 "In7.Cu" mixed)
		(18 "In8.Cu" power)
		(2 "B.Cu" mixed)
		(9 "F.Adhes" user "F.Adhesive")
		(11 "B.Adhes" user "B.Adhesive")
		(13 "F.Paste" user)
		(15 "B.Paste" user)
		(5 "F.SilkS" user "F.Silkscreen")
		(7 "B.SilkS" user "B.Silkscreen")
		(1 "F.Mask" user)
		(3 "B.Mask" user)
		(17 "Dwgs.User" user "User.Drawings")
		(19 "Cmts.User" user "User.Comments")
		(21 "Eco1.User" user "User.Eco1")
		(23 "Eco2.User" user "User.Eco2")
		(25 "Edge.Cuts" user)
		(27 "Margin" user)
		(31 "F.CrtYd" user "F.Courtyard")
		(29 "B.CrtYd" user "B.Courtyard")
		(35 "F.Fab" user)
		(33 "B.Fab" user)
	)
	(footprint "antmicro-footprints:C_0402_1005Metric"
		(layer "F.Cu")
		(at 209.35 157.09 90)
		(descr "Capacitor SMD 0402")
		(tags "capacitor SMD 0402")
		(property "Reference" "C210"
			(at -1.41 -0.5 90)
			(layer "F.SilkS")
			(effects
				(font
					(size 0.7 0.7)
					(thickness 0.15)
				)
				(justify left bottom)
			)
		)
		(property "Value" "C_100n_0402"
			(at 0 1.4 90)
			(layer "F.Fab")
			(effects
				(font
					(size 0.7 0.7)
					(thickness 0.15)
				)
				(justify left bottom)
			)
		)
		(property "Description" "SMD Multilayer Ceramic Capacitor, 0.1 µF, 50 V, 0402 [1005 Metric], ± 10%, X5R, GRM Series"
			(at 0 0 90)
			(layer "F.Fab")
			(hide yes)
			(effects
				(font
					(size 1.27 1.27)
					(thickness 0.15)
				)
			)
		)
		(property "Author" "Antmicro"
			(at 366.44 -52.26 0)
			(layer "F.Fab")
			(hide yes)
			(effects
				(font
					(size 1 1)
					(thickness 0.15)
				)
			)
		)
		(property "Dielectric" "X5R"
			(at 366.44 -52.26 0)
			(layer "F.Fab")
			(hide yes)
			(effects
				(font
					(size 1 1)
					(thickness 0.15)
				)
			)
		)
		(property "License" "Apache-2.0"
			(at 366.44 -52.26 0)
			(layer "F.Fab")
			(hide yes)
			(effects
				(font
					(size 1 1)
					(thickness 0.15)
				)
			)
		)
		(property "MPN" "GRM155R61H104KE14D"
			(at 366.44 -52.26 0)
			(layer "F.Fab")
			(hide yes)
			(effects
				(font
					(size 1 1)
					(thickness 0.15)
				)
			)
		)
		(property "Manufacturer" "Murata"
			(at 366.44 -52.26 0)
			(layer "F.Fab")
			(hide yes)
			(effects
				(font
					(size 1 1)
					(thickness 0.15)
				)
			)
		)
		(property "Val" "100n"
			(at 366.44 -52.26 0)
			(layer "F.Fab")
			(hide yes)
			(effects
				(font
					(size 1 1)
					(thickness 0.15)
				)
			)
		)
		(property "Voltage" "50V"
			(at 366.44 -52.26 0)
			(layer "F.Fab")
			(hide yes)
			(effects
				(font
					(size 1 1)
					(thickness 0.15)
				)
			)
		)
		(sheetname "SPI Flash + SD Card")
		(sheetfile "spi-flash.kicad_sch")
		(attr smd)
		(fp_rect
			(start -0.925 -0.47)
			(end 0.925 0.47)
			(stroke
				(width 0.05)
				(type default)
			)
			(fill no)
			(layer "F.CrtYd")
		)
		(fp_line
			(start 0.504 -0.25)
			(end 0.504 0.248)
			(stroke
				(width 0.15)
				(type solid)
			)
			(layer "F.Fab")
		)
		(fp_line
			(start -0.494 -0.25)
			(end 0.504 -0.25)
			(stroke
				(width 0.15)
				(type solid)
			)
			(layer "F.Fab")
		)
		(fp_line
			(start 0.504 0.248)
			(end -0.494 0.248)
			(stroke
				(width 0.15)
				(type solid)
			)
			(layer "F.Fab")
		)
		(fp_line
			(start -0.494 0.248)
			(end -0.494 -0.25)
			(stroke
				(width 0.15)
				(type solid)
			)
			(layer "F.Fab")
		)
		(pad "1" smd roundrect
			(at -0.48 0 90)
			(size 0.59 0.64)
			(layers "F.Cu" "F.Mask" "F.Paste")
			(roundrect_rratio 0.25)
			(net 1 "GND")
			(pintype "passive")
		)
		(pad "2" smd roundrect
			(at 0.48 0 90)
			(size 0.59 0.64)
			(layers "F.Cu" "F.Mask" "F.Paste")
			(roundrect_rratio 0.25)
			(net 26 "+1V8")
			(pintype "passive")
		)
	)
	(footprint "antmicro-footprints:SC70-3"
		(layer "F.Cu")
		(at 207.4 78.79 90)
		(property "Reference" "Q1"
			(at -2.31 -1.8 180)
			(layer "F.SilkS")
			(effects
				(font
					(size 0.7 0.7)
					(thickness 0.15)
				)
				(justify left bottom)
			)
		)
		(property "Value" "BSS138PW"
			(at 0 2.3 90)
			(layer "F.Fab")
			(effects
				(font
					(size 0.7 0.7)
					(thickness 0.15)
				)
				(justify left bottom)
			)
		)
		(property "Description" "Power MOSFET, N Channel, 60 V, 320 mA, 0.9 ohm, SOT-323, Surface Mount"
			(at 0 0 90)
			(layer "F.Fab")
			(hide yes)
			(effects
				(font
					(size 1.27 1.27)
					(thickness 0.15)
				)
			)
		)
		(property "Author" "Antmicro"
			(at 286.19 -128.61 0)
			(layer "F.Fab")
			(hide yes)
			(effects
				(font
					(size 1 1)
					(thickness 0.15)
				)
			)
		)
		(property "License" "Apache-2.0"
			(at 286.19 -128.61 0)
			(layer "F.Fab")
			(hide yes)
			(effects
				(font
					(size 1 1)
					(thickness 0.15)
				)
			)
		)
		(property "MPN" "BSS138PW"
			(at 286.19 -128.61 0)
			(layer "F.Fab")
			(hide yes)
			(effects
				(font
					(size 1 1)
					(thickness 0.15)
				)
			)
		)
		(property "Manufacturer" "Nexperia"
			(at 286.19 -128.61 0)
			(layer "F.Fab")
			(hide yes)
			(effects
				(font
					(size 1 1)
					(thickness 0.15)
				)
			)
		)
		(sheetname "FPGA Config")
		(sheetfile "fpga-config.kicad_sch")
		(attr smd)
		(fp_line
			(start -0.3 -1)
			(end 0.627 -0.999)
			(stroke
				(width 0.15)
				(type solid)
			)
			(layer "F.SilkS")
		)
		(fp_line
			(start 0.627 -0.6)
			(end 0.627 -0.999)
			(stroke
				(width 0.15)
				(type solid)
			)
			(layer "F.SilkS")
		)
		(fp_line
			(start 0.627 0.6)
			(end 0.627 1.001)
			(stroke
				(width 0.15)
				(type solid)
			)
			(layer "F.SilkS")
		)
		(fp_line
			(start -0.3 1)
			(end 0.627 1.001)
			(stroke
				(width 0.15)
				(type solid)
			)
			(layer "F.SilkS")
		)
		(fp_line
			(start 0.9 -1.3)
			(end 0.9 -0.4)
			(stroke
				(width 0.05)
				(type solid)
			)
			(layer "F.CrtYd")
		)
		(fp_line
			(start -0.9 -1.3)
			(end 0.9 -1.3)
			(stroke
				(width 0.05)
				(type solid)
			)
			(layer "F.CrtYd")
		)
		(fp_line
			(start -0.9 -1.3)
			(end -0.9 -1)
			(stroke
				(width 0.05)
				(type solid)
			)
			(layer "F.CrtYd")
		)
		(fp_line
			(start -0.9 -1)
			(end -1.4 -1)
			(stroke
				(width 0.05)
				(type solid)
			)
			(layer "F.CrtYd")
		)
		(fp_line
			(start 1.4 -0.4)
			(end 1.4 0.4)
			(stroke
				(width 0.05)
				(type solid)
			)
			(layer "F.CrtYd")
		)
		(fp_line
			(start 0.9 -0.4)
			(end 1.4 -0.4)
			(stroke
				(width 0.05)
				(type solid)
			)
			(layer "F.CrtYd")
		)
		(fp_line
			(start 1.4 0.4)
			(end 0.9 0.4)
			(stroke
				(width 0.05)
				(type solid)
			)
			(layer "F.CrtYd")
		)
		(fp_line
			(start 0.9 0.4)
			(end 0.9 1.3)
			(stroke
				(width 0.05)
				(type solid)
			)
			(layer "F.CrtYd")
		)
		(fp_line
			(start -0.9 1)
			(end -1.4 1)
			(stroke
				(width 0.05)
				(type solid)
			)
			(layer "F.CrtYd")
		)
		(fp_line
			(start -1.4 1)
			(end -1.4 -1)
			(stroke
				(width 0.05)
				(type solid)
			)
			(layer "F.CrtYd")
		)
		(fp_line
			(start 0.9 1.3)
			(end -0.9 1.3)
			(stroke
				(width 0.05)
				(type solid)
			)
			(layer "F.CrtYd")
		)
		(fp_line
			(start -0.9 1.3)
			(end -0.9 1)
			(stroke
				(width 0.05)
				(type solid)
			)
			(layer "F.CrtYd")
		)
		(fp_rect
			(start -0.623 -0.999)
			(end 0.627 1.001)
			(stroke
				(width 0.15)
				(type solid)
			)
			(fill no)
			(layer "F.Fab")
		)
		(pad "1" smd rect
			(at -1.051 -0.65 180)
			(size 0.6 0.6)
			(layers "F.Cu" "F.Mask" "F.Paste")
			(net 246 "/FPGA Config/DONE")
			(pinfunction "G")
			(pintype "bidirectional")
		)
		(pad "2" smd rect
			(at -1.051 0.65 180)
			(size 0.6 0.6)
			(layers "F.Cu" "F.Mask" "F.Paste")
			(net 1 "GND")
			(pinfunction "S")
			(pintype "bidirectional")
		)
		(pad "3" smd rect
			(at 1.05 0 180)
			(size 0.6 0.6)
			(layers "F.Cu" "F.Mask" "F.Paste")
			(net 333 "Net-(Q1-D)")
			(pinfunction "D")
			(pintype "bidirectional")
		)
	)
	(footprint "antmicro-footprints:C_0805_2012Metric"
		(layer "F.Cu")
		(at 159.0125 176.2)
		(descr "Capacitor SMD 0805")
		(tags "capacitor SMD 0805")
		(property "Reference" "C315"
			(at 2.4875 1.8 0)
			(layer "F.SilkS")
			(effects
				(font
					(size 0.7 0.7)
					(thickness 0.15)
				)
				(justify left bottom)
			)
		)
		(property "Value" "C_22u_25V_0805"
			(at 0 1.947 0)
			(layer "F.Fab")
			(effects
				(font
					(size 0.7 0.7)
					(thickness 0.15)
				)
				(justify left bottom)
			)
		)
		(property "Description" "SMT Multilayer Ceramic Capacitor, 22uF, +/-20%, 25V, X5R, 0805 [2012 Metric]"
			(at 0 0 0)
			(layer "F.Fab")
			(hide yes)
			(effects
				(font
					(size 1.27 1.27)
					(thickness 0.15)
				)
			)
		)
		(property "Author" "Antmicro"
			(at 0 0 0)
			(layer "F.Fab")
			(hide yes)
			(effects
				(font
					(size 1 1)
					(thickness 0.15)
				)
			)
		)
		(property "Dielectric" "X5R"
			(at 0 0 0)
			(layer "F.Fab")
			(hide yes)
			(effects
				(font
					(size 1 1)
					(thickness 0.15)
				)
			)
		)
		(property "License" "Apache-2.0"
			(at 0 0 0)
			(layer "F.Fab")
			(hide yes)
			(effects
				(font
					(size 1 1)
					(thickness 0.15)
				)
			)
		)
		(property "MPN" "CL21A226MAYNNNE"
			(at 0 0 0)
			(layer "F.Fab")
			(hide yes)
			(effects
				(font
					(size 1 1)
					(thickness 0.15)
				)
			)
		)
		(property "Manufacturer" "Samsung Electro-Mechanics"
			(at 0 0 0)
			(layer "F.Fab")
			(hide yes)
			(effects
				(font
					(size 1 1)
					(thickness 0.15)
				)
			)
		)
		(property "Val" "22u"
			(at 0 0 0)
			(layer "F.Fab")
			(hide yes)
			(effects
				(font
					(size 1 1)
					(thickness 0.15)
				)
			)
		)
		(property "Voltage" "25V"
			(at 0 0 0)
			(layer "F.Fab")
			(hide yes)
			(effects
				(font
					(size 1 1)
					(thickness 0.15)
				)
			)
		)
		(sheetname "DC-DC Converters")
		(sheetfile "dc-dc.kicad_sch")
		(attr smd)
		(fp_line
			(start -0.3 -0.7)
			(end 0.3 -0.7)
			(stroke
				(width 0.15)
				(type solid)
			)
			(layer "F.SilkS")
		)
		(fp_line
			(start -0.3 0.7)
			(end 0.3 0.7)
			(stroke
				(width 0.15)
				(type solid)
			)
			(layer "F.SilkS")
		)
		(fp_rect
			(start 1.95 -0.9)
			(end -1.95 0.9)
			(stroke
				(width 0.05)
				(type default)
			)
			(fill no)
			(layer "F.CrtYd")
		)
		(fp_rect
			(start -0.95 -0.675)
			(end 0.95 0.675)
			(stroke
				(width 0.15)
				(type solid)
			)
			(fill no)
			(layer "F.Fab")
		)
		(pad "1" smd roundrect
			(at -1.1 0)
			(size 1.2 1.3)
			(layers "F.Cu" "F.Mask" "F.Paste")
			(roundrect_rratio 0.25)
			(net 1 "GND")
			(pintype "passive")
		)
		(pad "2" smd roundrect
			(at 1.1 0)
			(size 1.2 1.3)
			(layers "F.Cu" "F.Mask" "F.Paste")
			(roundrect_rratio 0.25)
			(net 702 "VDC")
			(pintype "passive")
		)
	)
	(footprint "antmicro-footprints:R_0402_1005Metric"
		(layer "F.Cu")
		(at 242.15 109.5)
		(descr "Resistor SMD 0402")
		(tags "resistor SMD 0402")
		(property "Reference" "R260"
			(at -3.65 0.35 0)
			(layer "F.SilkS")
			(effects
				(font
					(size 0.7 0.7)
					(thickness 0.15)
				)
				(justify left bottom)
			)
		)
		(property "Value" "R_0R_0402"
			(at 0 1.4 0)
			(layer "F.Fab")
			(effects
				(font
					(size 0.7 0.7)
					(thickness 0.15)
				)
				(justify left bottom)
			)
		)
		(property "Description" "SMD Chip Resistor, Jumper, 0 ohm, 100 mW, 0402 [1005 Metric], Thick Film, General Purpose"
			(at 0 0 0)
			(layer "F.Fab")
			(hide yes)
			(effects
				(font
					(size 1.27 1.27)
					(thickness 0.15)
				)
			)
		)
		(property "Author" "Antmicro"
			(at 0 0 0)
			(layer "F.Fab")
			(hide yes)
			(effects
				(font
					(size 1 1)
					(thickness 0.15)
				)
			)
		)
		(property "Current" "1A"
			(at 0 0 0)
			(layer "F.Fab")
			(hide yes)
			(effects
				(font
					(size 1 1)
					(thickness 0.15)
				)
			)
		)
		(property "License" "Apache-2.0"
			(at 0 0 0)
			(layer "F.Fab")
			(hide yes)
			(effects
				(font
					(size 1 1)
					(thickness 0.15)
				)
			)
		)
		(property "MPN" "ERJ2GE0R00X"
			(at 0 0 0)
			(layer "F.Fab")
			(hide yes)
			(effects
				(font
					(size 1 1)
					(thickness 0.15)
				)
			)
		)
		(property "Manufacturer" "Panasonic"
			(at 0 0 0)
			(layer "F.Fab")
			(hide yes)
			(effects
				(font
					(size 1 1)
					(thickness 0.15)
				)
			)
		)
		(property "Tolerance" ""
			(at 0 0 0)
			(layer "F.Fab")
			(hide yes)
			(effects
				(font
					(size 1 1)
					(thickness 0.15)
				)
			)
		)
		(property "Val" "0R"
			(at 0 0 0)
			(layer "F.Fab")
			(hide yes)
			(effects
				(font
					(size 1 1)
					(thickness 0.15)
				)
			)
		)
		(sheetname "HDMI + Ethernet")
		(sheetfile "hdmi-ethernet.kicad_sch")
		(attr smd)
		(fp_rect
			(start -0.925 -0.47)
			(end 0.925 0.47)
			(stroke
				(width 0.05)
				(type default)
			)
			(fill no)
			(layer "F.CrtYd")
		)
		(fp_rect
			(start -0.5 -0.25)
			(end 0.5 0.25)
			(stroke
				(width 0.15)
				(type solid)
			)
			(fill no)
			(layer "F.Fab")
		)
		(pad "1" smd roundrect
			(at -0.48 0)
			(size 0.59 0.64)
			(layers "F.Cu" "F.Mask" "F.Paste")
			(roundrect_rratio 0.25)
			(net 530 "/FPGA Bank 16 & 17/HDMI.CLK_P")
			(pintype "passive")
		)
		(pad "2" smd roundrect
			(at 0.48 0)
			(size 0.59 0.64)
			(layers "F.Cu" "F.Mask" "F.Paste")
			(roundrect_rratio 0.25)
			(net 861 "/HDMI + Ethernet/HDMI_CONN_CLK_P")
			(pintype "passive")
		)
	)
	(footprint "antmicro-footprints:R_0402_1005Metric"
		(layer "F.Cu")
		(at 224.8 163.4 180)
		(descr "Resistor SMD 0402")
		(tags "resistor SMD 0402")
		(property "Reference" "R51"
			(at 1.1 -1.25 180)
			(layer "F.SilkS")
			(effects
				(font
					(size 0.7 0.7)
					(thickness 0.15)
				)
				(justify left bottom)
			)
		)
		(property "Value" "R_22k_0402"
			(at 0 1.4 180)
			(layer "F.Fab")
			(effects
				(font
					(size 0.7 0.7)
					(thickness 0.15)
				)
				(justify left bottom)
			)
		)
		(property "Description" "SMD Chip Resistor, 22 kohm, ± 1%, 62.5 mW, 0402 [1005 Metric], Thick Film, General Purpose"
			(at 0 0 180)
			(layer "F.Fab")
			(hide yes)
			(effects
				(font
					(size 1.27 1.27)
					(thickness 0.15)
				)
			)
		)
		(property "Author" "Antmicro"
			(at 449.6 326.8 0)
			(layer "F.Fab")
			(hide yes)
			(effects
				(font
					(size 1 1)
					(thickness 0.15)
				)
			)
		)
		(property "License" "Apache-2.0"
			(at 449.6 326.8 0)
			(layer "F.Fab")
			(hide yes)
			(effects
				(font
					(size 1 1)
					(thickness 0.15)
				)
			)
		)
		(property "MPN" "CR0402-FX-2202GLF"
			(at 449.6 326.8 0)
			(layer "F.Fab")
			(hide yes)
			(effects
				(font
					(size 1 1)
					(thickness 0.15)
				)
			)
		)
		(property "Manufacturer" "Bourns"
			(at 449.6 326.8 0)
			(layer "F.Fab")
			(hide yes)
			(effects
				(font
					(size 1 1)
					(thickness 0.15)
				)
			)
		)
		(property "Tolerance" "1%"
			(at 449.6 326.8 0)
			(layer "F.Fab")
			(hide yes)
			(effects
				(font
					(size 1 1)
					(thickness 0.15)
				)
			)
		)
		(property "Val" "22k"
			(at 449.6 326.8 0)
			(layer "F.Fab")
			(hide yes)
			(effects
				(font
					(size 1 1)
					(thickness 0.15)
				)
			)
		)
		(sheetname "Power supply")
		(sheetfile "power-supply.kicad_sch")
		(attr smd)
		(fp_rect
			(start -0.925 -0.47)
			(end 0.925 0.47)
			(stroke
				(width 0.05)
				(type default)
			)
			(fill no)
			(layer "F.CrtYd")
		)
		(fp_rect
			(start -0.5 -0.25)
			(end 0.5 0.25)
			(stroke
				(width 0.15)
				(type solid)
			)
			(fill no)
			(layer "F.Fab")
		)
		(pad "1" smd roundrect
			(at -0.48 0 180)
			(size 0.59 0.64)
			(layers "F.Cu" "F.Mask" "F.Paste")
			(roundrect_rratio 0.25)
			(net 362 "Net-(U6-VBUS_EN_SNK)")
			(pintype "passive")
		)
		(pad "2" smd roundrect
			(at 0.48 0 180)
			(size 0.59 0.64)
			(layers "F.Cu" "F.Mask" "F.Paste")
			(roundrect_rratio 0.25)
			(net 872 "/Power supply/SINK_EN")
			(pintype "passive")
		)
	)
	(footprint "antmicro-footprints:C_0402_1005Metric"
		(layer "F.Cu")
		(at 195.8375 97.0865)
		(descr "Capacitor SMD 0402")
		(tags "capacitor SMD 0402")
		(property "Reference" "C254"
			(at -1.4875 1.2635 0)
			(layer "F.SilkS")
			(effects
				(font
					(size 0.7 0.7)
					(thickness 0.15)
				)
				(justify left bottom)
			)
		)
		(property "Value" "C_10u_0402"
			(at 0 1.4 0)
			(layer "F.Fab")
			(effects
				(font
					(size 0.7 0.7)
					(thickness 0.15)
				)
				(justify left bottom)
			)
		)
		(property "Description" "SMD Multilayer Ceramic Capacitor, 10 µF, 6.3 V, 0402 [1005 Metric], ± 20%, X5R, CC Series"
			(at 0 0 0)
			(layer "F.Fab")
			(hide yes)
			(effects
				(font
					(size 1.27 1.27)
					(thickness 0.15)
				)
			)
		)
		(property "Author" "Antmicro"
			(at 0 0 0)
			(layer "F.Fab")
			(hide yes)
			(effects
				(font
					(size 1 1)
					(thickness 0.15)
				)
			)
		)
		(property "Dielectric" ""
			(at 0 0 0)
			(layer "F.Fab")
			(hide yes)
			(effects
				(font
					(size 1 1)
					(thickness 0.15)
				)
			)
		)
		(property "License" "Apache-2.0"
			(at 0 0 0)
			(layer "F.Fab")
			(hide yes)
			(effects
				(font
					(size 1 1)
					(thickness 0.15)
				)
			)
		)
		(property "MPN" "CC0402MRX5R5BB106"
			(at 0 0 0)
			(layer "F.Fab")
			(hide yes)
			(effects
				(font
					(size 1 1)
					(thickness 0.15)
				)
			)
		)
		(property "Manufacturer" "YAGEO"
			(at 0 0 0)
			(layer "F.Fab")
			(hide yes)
			(effects
				(font
					(size 1 1)
					(thickness 0.15)
				)
			)
		)
		(property "Val" "10u"
			(at 0 0 0)
			(layer "F.Fab")
			(hide yes)
			(effects
				(font
					(size 1 1)
					(thickness 0.15)
				)
			)
		)
		(property "Voltage" ""
			(at 0 0 0)
			(layer "F.Fab")
			(hide yes)
			(effects
				(font
					(size 1 1)
					(thickness 0.15)
				)
			)
		)
		(sheetname "HDMI + Ethernet")
		(sheetfile "hdmi-ethernet.kicad_sch")
		(attr smd)
		(fp_rect
			(start -0.925 -0.47)
			(end 0.925 0.47)
			(stroke
				(width 0.05)
				(type default)
			)
			(fill no)
			(layer "F.CrtYd")
		)
		(fp_line
			(start -0.494 -0.25)
			(end 0.504 -0.25)
			(stroke
				(width 0.15)
				(type solid)
			)
			(layer "F.Fab")
		)
		(fp_line
			(start -0.494 0.248)
			(end -0.494 -0.25)
			(stroke
				(width 0.15)
				(type solid)
			)
			(layer "F.Fab")
		)
		(fp_line
			(start 0.504 -0.25)
			(end 0.504 0.248)
			(stroke
				(width 0.15)
				(type solid)
			)
			(layer "F.Fab")
		)
		(fp_line
			(start 0.504 0.248)
			(end -0.494 0.248)
			(stroke
				(width 0.15)
				(type solid)
			)
			(layer "F.Fab")
		)
		(pad "1" smd roundrect
			(at -0.48 0)
			(size 0.59 0.64)
			(layers "F.Cu" "F.Mask" "F.Paste")
			(roundrect_rratio 0.25)
			(net 1 "GND")
			(pintype "passive")
		)
		(pad "2" smd roundrect
			(at 0.48 0)
			(size 0.59 0.64)
			(layers "F.Cu" "F.Mask" "F.Paste")
			(roundrect_rratio 0.25)
			(net 24 "+3V3")
			(pintype "passive")
		)
	)
)
